(kicad_sch
	(version 20250114)
	(generator "eeschema")
	(generator_version "9.0")
	(paper "A3")
	(title_block
		(title "GMSL Deserializer")
		(date "2025-10-09")
		(rev "1.0.4")
		(company "Antmicro Ltd")
		(comment 1 "www.antmicro.com")
	)
	(junction
		(at 349.25 222.25)
		(diameter 0)
		(color 0 0 0 0)
	)
	(junction
		(at 349.25 242.57)
		(diameter 0)
		(color 0 0 0 0)
	)
	(junction
		(at 349.25 236.22)
		(diameter 0)
		(color 0 0 0 0)
	)
	(junction
		(at 349.25 228.6)
		(diameter 0)
		(color 0 0 0 0)
	)
	(wire
		(pts
			(xy 134.62 204.47) (xy 148.59 204.47)
		)
		(stroke
			(width 0)
			(type default)
		)
	)
	(wire
		(pts
			(xy 134.62 207.01) (xy 148.59 207.01)
		)
		(stroke
			(width 0)
			(type default)
		)
	)
	(wire
		(pts
			(xy 194.31 207.01) (xy 207.01 207.01)
		)
		(stroke
			(width 0)
			(type default)
		)
	)
	(bus
		(pts
			(xy 194.31 220.98) (xy 207.01 220.98)
		)
		(stroke
			(width 0)
			(type default)
		)
	)
	(wire
		(pts
			(xy 194.31 204.47) (xy 207.01 204.47)
		)
		(stroke
			(width 0)
			(type default)
		)
	)
	(wire
		(pts
			(xy 349.25 236.22) (xy 349.25 242.57)
		)
		(stroke
			(width 0)
			(type default)
		)
	)
	(wire
		(pts
			(xy 349.25 242.57) (xy 349.25 246.38)
		)
		(stroke
			(width 0)
			(type default)
		)
	)
	(wire
		(pts
			(xy 134.62 228.6) (xy 148.59 228.6)
		)
		(stroke
			(width 0)
			(type default)
		)
	)
	(wire
		(pts
			(xy 134.62 209.55) (xy 148.59 209.55)
		)
		(stroke
			(width 0)
			(type default)
		)
	)
	(wire
		(pts
			(xy 353.06 242.57) (xy 349.25 242.57)
		)
		(stroke
			(width 0)
			(type default)
		)
	)
	(wire
		(pts
			(xy 194.31 232.41) (xy 207.01 232.41)
		)
		(stroke
			(width 0)
			(type default)
		)
	)
	(wire
		(pts
			(xy 349.25 222.25) (xy 349.25 228.6)
		)
		(stroke
			(width 0)
			(type default)
		)
	)
	(wire
		(pts
			(xy 134.62 223.52) (xy 148.59 223.52)
		)
		(stroke
			(width 0)
			(type default)
		)
	)
	(wire
		(pts
			(xy 353.06 228.6) (xy 349.25 228.6)
		)
		(stroke
			(width 0)
			(type default)
		)
	)
	(wire
		(pts
			(xy 194.31 234.95) (xy 207.01 234.95)
		)
		(stroke
			(width 0)
			(type default)
		)
	)
	(wire
		(pts
			(xy 353.06 236.22) (xy 349.25 236.22)
		)
		(stroke
			(width 0)
			(type default)
		)
	)
	(bus
		(pts
			(xy 194.31 223.52) (xy 207.01 223.52)
		)
		(stroke
			(width 0)
			(type default)
		)
	)
	(bus
		(pts
			(xy 194.31 226.06) (xy 207.01 226.06)
		)
		(stroke
			(width 0)
			(type default)
		)
	)
	(wire
		(pts
			(xy 353.06 222.25) (xy 349.25 222.25)
		)
		(stroke
			(width 0)
			(type default)
		)
	)
	(wire
		(pts
			(xy 194.31 209.55) (xy 207.01 209.55)
		)
		(stroke
			(width 0)
			(type default)
		)
	)
	(wire
		(pts
			(xy 349.25 228.6) (xy 349.25 236.22)
		)
		(stroke
			(width 0)
			(type default)
		)
	)
	(wire
		(pts
			(xy 194.31 212.09) (xy 207.01 212.09)
		)
		(stroke
			(width 0)
			(type default)
		)
	)
	(wire
		(pts
			(xy 134.62 212.09) (xy 148.59 212.09)
		)
		(stroke
			(width 0)
			(type default)
		)
	)
	(symbol
		(lib_id "antmicroMechanicalParts:Spacer_Drill3.7mm_H6mm_9774060151R")
		(at 353.06 222.25 0)
		(unit 1)
		(exclude_from_sim no)
		(in_bom yes)
		(on_board yes)
		(dnp no)
		(fields_autoplaced yes)
		(property "Reference" "H1"
			(at 361.95 220.9799 0)
			(effects
				(font
					(size 1.27 1.27)
					(thickness 0.15)
				)
				(justify left)
			)
		)
		(property "Value" "Spacer_Drill3.7mm_H6mm_9774060151R"
			(at 361.95 223.5199 0)
			(effects
				(font
					(size 1.27 1.27)
					(thickness 0.15)
				)
				(justify left)
			)
		)
		(property "Footprint" "antmicro-footprints:Spacer_Drill3.7mm_H6mm_9774060151R"
			(at 375.92 229.87 0)
			(effects
				(font
					(size 1.27 1.27)
					(thickness 0.15)
				)
				(justify left bottom)
				(hide yes)
			)
		)
		(property "Datasheet" "https://www.we-online.com/components/products/datasheet/9774060151R.pdf"
			(at 375.92 232.41 0)
			(effects
				(font
					(size 1.27 1.27)
					(thickness 0.15)
				)
				(justify left bottom)
				(hide yes)
			)
		)
		(property "Description" "Spacer, SMT, Non Stop, Steel, Swage Round, 5.1 mm x 6 mm, M2.5 Thread, WA-SMSI Series"
			(at 353.06 222.25 0)
			(effects
				(font
					(size 1.27 1.27)
				)
				(hide yes)
			)
		)
		(property "Manufacturer" "Würth Elektronik"
			(at 375.92 234.95 0)
			(effects
				(font
					(size 1.27 1.27)
					(thickness 0.15)
				)
				(justify left bottom)
				(hide yes)
			)
		)
		(property "MPN" "9774060151R"
			(at 375.92 237.49 0)
			(effects
				(font
					(size 1.27 1.27)
					(thickness 0.15)
				)
				(justify left bottom)
				(hide yes)
			)
		)
		(property "Author" "Antmicro"
			(at 375.92 240.03 0)
			(effects
				(font
					(size 1.27 1.27)
					(thickness 0.15)
				)
				(justify left bottom)
				(hide yes)
			)
		)
		(property "License" "Apache-2.0"
			(at 375.92 242.57 0)
			(effects
				(font
					(size 1.27 1.27)
					(thickness 0.15)
				)
				(justify left bottom)
				(hide yes)
			)
		)
		(pin "1"
		)
		(instances
			(project "gmsl-deserializer"
				(path ""
					(reference "H1")
					(unit 1)
				)
			)
		)
	)
	(symbol
		(lib_id "antmicroMechanicalParts:Spacer_Drill3.7mm_H6mm_9774060151R")
		(at 353.06 228.6 0)
		(unit 1)
		(exclude_from_sim no)
		(in_bom yes)
		(on_board yes)
		(dnp no)
		(fields_autoplaced yes)
		(property "Reference" "H2"
			(at 361.95 227.3299 0)
			(effects
				(font
					(size 1.27 1.27)
					(thickness 0.15)
				)
				(justify left)
			)
		)
		(property "Value" "Spacer_Drill3.7mm_H6mm_9774060151R"
			(at 361.95 229.8699 0)
			(effects
				(font
					(size 1.27 1.27)
					(thickness 0.15)
				)
				(justify left)
			)
		)
		(property "Footprint" "antmicro-footprints:Spacer_Drill3.7mm_H6mm_9774060151R"
			(at 375.92 236.22 0)
			(effects
				(font
					(size 1.27 1.27)
					(thickness 0.15)
				)
				(justify left bottom)
				(hide yes)
			)
		)
		(property "Datasheet" "https://www.we-online.com/components/products/datasheet/9774060151R.pdf"
			(at 375.92 238.76 0)
			(effects
				(font
					(size 1.27 1.27)
					(thickness 0.15)
				)
				(justify left bottom)
				(hide yes)
			)
		)
		(property "Description" "Spacer, SMT, Non Stop, Steel, Swage Round, 5.1 mm x 6 mm, M2.5 Thread, WA-SMSI Series"
			(at 353.06 228.6 0)
			(effects
				(font
					(size 1.27 1.27)
				)
				(hide yes)
			)
		)
		(property "Manufacturer" "Würth Elektronik"
			(at 375.92 241.3 0)
			(effects
				(font
					(size 1.27 1.27)
					(thickness 0.15)
				)
				(justify left bottom)
				(hide yes)
			)
		)
		(property "MPN" "9774060151R"
			(at 375.92 243.84 0)
			(effects
				(font
					(size 1.27 1.27)
					(thickness 0.15)
				)
				(justify left bottom)
				(hide yes)
			)
		)
		(property "Author" "Antmicro"
			(at 375.92 246.38 0)
			(effects
				(font
					(size 1.27 1.27)
					(thickness 0.15)
				)
				(justify left bottom)
				(hide yes)
			)
		)
		(property "License" "Apache-2.0"
			(at 375.92 248.92 0)
			(effects
				(font
					(size 1.27 1.27)
					(thickness 0.15)
				)
				(justify left bottom)
				(hide yes)
			)
		)
		(pin "1"
		)
		(instances
			(project "gmsl-deserializer"
				(path ""
					(reference "H2")
					(unit 1)
				)
			)
		)
	)
	(symbol
		(lib_id "antmicropower:GND")
		(at 349.25 246.38 0)
		(unit 1)
		(exclude_from_sim no)
		(in_bom yes)
		(on_board yes)
		(dnp no)
		(property "Reference" "#PWR0100"
			(at 358.14 248.92 0)
			(effects
				(font
					(size 1.27 1.27)
					(thickness 0.15)
				)
				(justify left bottom)
				(hide yes)
			)
		)
		(property "Value" "GND"
			(at 349.25 250.19 0)
			(effects
				(font
					(size 1.27 1.27)
					(thickness 0.15)
				)
			)
		)
		(property "Footprint" ""
			(at 358.14 254 0)
			(effects
				(font
					(size 1.27 1.27)
					(thickness 0.15)
				)
				(justify left bottom)
				(hide yes)
			)
		)
		(property "Datasheet" ""
			(at 358.14 259.08 0)
			(effects
				(font
					(size 1.27 1.27)
					(thickness 0.15)
				)
				(justify left bottom)
				(hide yes)
			)
		)
		(property "Description" ""
			(at 349.25 246.38 0)
			(effects
				(font
					(size 1.27 1.27)
				)
				(hide yes)
			)
		)
		(property "Author" "Antmicro"
			(at 358.14 254 0)
			(effects
				(font
					(size 1.27 1.27)
					(thickness 0.15)
				)
				(justify left bottom)
				(hide yes)
			)
		)
		(property "License" "Apache-2.0"
			(at 358.14 256.54 0)
			(effects
				(font
					(size 1.27 1.27)
					(thickness 0.15)
				)
				(justify left bottom)
				(hide yes)
			)
		)
		(pin "1"
		)
		(instances
			(project "gmsl-deserializer"
				(path ""
					(reference "#PWR0100")
					(unit 1)
				)
			)
		)
	)
	(symbol
		(lib_id "antmicroMechanicalParts:Spacer_Drill3.7mm_H6mm_9774060151R")
		(at 353.06 236.22 0)
		(unit 1)
		(exclude_from_sim no)
		(in_bom yes)
		(on_board yes)
		(dnp no)
		(fields_autoplaced yes)
		(property "Reference" "H3"
			(at 361.95 234.9499 0)
			(effects
				(font
					(size 1.27 1.27)
					(thickness 0.15)
				)
				(justify left)
			)
		)
		(property "Value" "Spacer_Drill3.7mm_H6mm_9774060151R"
			(at 361.95 237.4899 0)
			(effects
				(font
					(size 1.27 1.27)
					(thickness 0.15)
				)
				(justify left)
			)
		)
		(property "Footprint" "antmicro-footprints:Spacer_Drill3.7mm_H6mm_9774060151R"
			(at 375.92 243.84 0)
			(effects
				(font
					(size 1.27 1.27)
					(thickness 0.15)
				)
				(justify left bottom)
				(hide yes)
			)
		)
		(property "Datasheet" "https://www.we-online.com/components/products/datasheet/9774060151R.pdf"
			(at 375.92 246.38 0)
			(effects
				(font
					(size 1.27 1.27)
					(thickness 0.15)
				)
				(justify left bottom)
				(hide yes)
			)
		)
		(property "Description" "Spacer, SMT, Non Stop, Steel, Swage Round, 5.1 mm x 6 mm, M2.5 Thread, WA-SMSI Series"
			(at 353.06 236.22 0)
			(effects
				(font
					(size 1.27 1.27)
				)
				(hide yes)
			)
		)
		(property "Manufacturer" "Würth Elektronik"
			(at 375.92 248.92 0)
			(effects
				(font
					(size 1.27 1.27)
					(thickness 0.15)
				)
				(justify left bottom)
				(hide yes)
			)
		)
		(property "MPN" "9774060151R"
			(at 375.92 251.46 0)
			(effects
				(font
					(size 1.27 1.27)
					(thickness 0.15)
				)
				(justify left bottom)
				(hide yes)
			)
		)
		(property "Author" "Antmicro"
			(at 375.92 254 0)
			(effects
				(font
					(size 1.27 1.27)
					(thickness 0.15)
				)
				(justify left bottom)
				(hide yes)
			)
		)
		(property "License" "Apache-2.0"
			(at 375.92 256.54 0)
			(effects
				(font
					(size 1.27 1.27)
					(thickness 0.15)
				)
				(justify left bottom)
				(hide yes)
			)
		)
		(pin "1"
		)
		(instances
			(project "gmsl-deserializer"
				(path ""
					(reference "H3")
					(unit 1)
				)
			)
		)
	)
	(symbol
		(lib_id "antmicroMechanicalParts:Spacer_Drill3.7mm_H6mm_9774060151R")
		(at 353.06 242.57 0)
		(unit 1)
		(exclude_from_sim no)
		(in_bom yes)
		(on_board yes)
		(dnp no)
		(fields_autoplaced yes)
		(property "Reference" "H4"
			(at 361.95 241.2999 0)
			(effects
				(font
					(size 1.27 1.27)
					(thickness 0.15)
				)
				(justify left)
			)
		)
		(property "Value" "Spacer_Drill3.7mm_H6mm_9774060151R"
			(at 361.95 243.8399 0)
			(effects
				(font
					(size 1.27 1.27)
					(thickness 0.15)
				)
				(justify left)
			)
		)
		(property "Footprint" "antmicro-footprints:Spacer_Drill3.7mm_H6mm_9774060151R"
			(at 375.92 250.19 0)
			(effects
				(font
					(size 1.27 1.27)
					(thickness 0.15)
				)
				(justify left bottom)
				(hide yes)
			)
		)
		(property "Datasheet" "https://www.we-online.com/components/products/datasheet/9774060151R.pdf"
			(at 375.92 252.73 0)
			(effects
				(font
					(size 1.27 1.27)
					(thickness 0.15)
				)
				(justify left bottom)
				(hide yes)
			)
		)
		(property "Description" "Spacer, SMT, Non Stop, Steel, Swage Round, 5.1 mm x 6 mm, M2.5 Thread, WA-SMSI Series"
			(at 353.06 242.57 0)
			(effects
				(font
					(size 1.27 1.27)
				)
				(hide yes)
			)
		)
		(property "Manufacturer" "Würth Elektronik"
			(at 375.92 255.27 0)
			(effects
				(font
					(size 1.27 1.27)
					(thickness 0.15)
				)
				(justify left bottom)
				(hide yes)
			)
		)
		(property "MPN" "9774060151R"
			(at 375.92 257.81 0)
			(effects
				(font
					(size 1.27 1.27)
					(thickness 0.15)
				)
				(justify left bottom)
				(hide yes)
			)
		)
		(property "Author" "Antmicro"
			(at 375.92 260.35 0)
			(effects
				(font
					(size 1.27 1.27)
					(thickness 0.15)
				)
				(justify left bottom)
				(hide yes)
			)
		)
		(property "License" "Apache-2.0"
			(at 375.92 262.89 0)
			(effects
				(font
					(size 1.27 1.27)
					(thickness 0.15)
				)
				(justify left bottom)
				(hide yes)
			)
		)
		(pin "1"
		)
		(instances
			(project "gmsl-deserializer"
				(path ""
					(reference "H4")
					(unit 1)
				)
			)
		)
	)
	(symbol
		(lib_id "antmicropower:PWR_FLAG")
		(at 349.25 222.25 0)
		(unit 1)
		(exclude_from_sim no)
		(in_bom yes)
		(on_board yes)
		(dnp no)
		(property "Reference" "#FLG0103"
			(at 349.25 220.345 0)
			(effects
				(font
					(size 1.27 1.27)
				)
				(hide yes)
			)
		)
		(property "Value" "PWR_FLAG"
			(at 349.25 218.44 0)
			(effects
				(font
					(size 1.27 1.27)
				)
			)
		)
		(property "Footprint" ""
			(at 349.25 222.25 0)
			(effects
				(font
					(size 1.27 1.27)
				)
				(hide yes)
			)
		)
		(property "Datasheet" ""
			(at 349.25 222.25 0)
			(effects
				(font
					(size 1.27 1.27)
				)
				(hide yes)
			)
		)
		(property "Description" ""
			(at 349.25 222.25 0)
			(effects
				(font
					(size 1.27 1.27)
				)
				(hide yes)
			)
		)
		(pin "1"
		)
		(instances
			(project "gmsl-deserializer"
				(path ""
					(reference "#FLG0103")
					(unit 1)
				)
			)
		)
	)
	(sheet
		(at 88.9 199.39)
		(size 45.72 39.37)
		(exclude_from_sim no)
		(in_bom yes)
		(on_board yes)
		(dnp no)
		(fields_autoplaced yes)
		(stroke
			(width 0.1524)
			(type solid)
		)
		(fill
			(color 0 0 0 0.0000)
		)
		(property "Sheetname" "Power"
			(at 88.9 198.6784 0)
			(effects
				(font
					(size 1.27 1.27)
				)
				(justify left bottom)
			)
		)
		(property "Sheetfile" "power.kicad_sch"
			(at 88.9 239.3446 0)
			(effects
				(font
					(size 1.27 1.27)
				)
				(justify left top)
			)
		)
		(pin "PoCD" output
			(at 134.62 212.09 0)
			(effects
				(font
					(size 1.27 1.27)
				)
				(justify right)
			)
		)
		(pin "PoCC" output
			(at 134.62 209.55 0)
			(effects
				(font
					(size 1.27 1.27)
				)
				(justify right)
			)
		)
		(pin "PoCA" output
			(at 134.62 204.47 0)
			(effects
				(font
					(size 1.27 1.27)
				)
				(justify right)
			)
		)
		(pin "PoCB" output
			(at 134.62 207.01 0)
			(effects
				(font
					(size 1.27 1.27)
				)
				(justify right)
			)
		)
		(pin "DC_IN" input
			(at 134.62 223.52 0)
			(effects
				(font
					(size 1.27 1.27)
				)
				(justify right)
			)
		)
		(pin "FFC_5V" input
			(at 134.62 228.6 0)
			(effects
				(font
					(size 1.27 1.27)
				)
				(justify right)
			)
		)
		(instances
			(project "gmsl-deserializer"
				(path ""
					(page "3")
				)
			)
		)
	)
	(sheet
		(at 207.01 199.39)
		(size 45.72 39.37)
		(exclude_from_sim no)
		(in_bom yes)
		(on_board yes)
		(dnp no)
		(fields_autoplaced yes)
		(stroke
			(width 0.1524)
			(type solid)
		)
		(fill
			(color 0 0 0 0.0000)
		)
		(property "Sheetname" "Deserializer"
			(at 207.01 198.6784 0)
			(effects
				(font
					(size 1.27 1.27)
				)
				(justify left bottom)
			)
		)
		(property "Sheetfile" "deserializer.kicad_sch"
			(at 207.01 239.3446 0)
			(effects
				(font
					(size 1.27 1.27)
				)
				(justify left top)
			)
		)
		(pin "MFP[0..8]" bidirectional
			(at 207.01 220.98 180)
			(effects
				(font
					(size 1.27 1.27)
				)
				(justify left)
			)
		)
		(pin "CSI0{CSI}" output
			(at 207.01 223.52 180)
			(effects
				(font
					(size 1.27 1.27)
				)
				(justify left)
			)
		)
		(pin "CSI1{CSI}" output
			(at 207.01 226.06 180)
			(effects
				(font
					(size 1.27 1.27)
				)
				(justify left)
			)
		)
		(pin "SDA" bidirectional
			(at 207.01 232.41 180)
			(effects
				(font
					(size 1.27 1.27)
				)
				(justify left)
			)
		)
		(pin "SCL" input
			(at 207.01 234.95 180)
			(effects
				(font
					(size 1.27 1.27)
				)
				(justify left)
			)
		)
		(pin "SIODP" bidirectional
			(at 207.01 212.09 180)
			(effects
				(font
					(size 1.27 1.27)
				)
				(justify left)
			)
		)
		(pin "SIOBP" bidirectional
			(at 207.01 207.01 180)
			(effects
				(font
					(size 1.27 1.27)
				)
				(justify left)
			)
		)
		(pin "SIOAP" bidirectional
			(at 207.01 204.47 180)
			(effects
				(font
					(size 1.27 1.27)
				)
				(justify left)
			)
		)
		(pin "SIOCP" bidirectional
			(at 207.01 209.55 180)
			(effects
				(font
					(size 1.27 1.27)
				)
				(justify left)
			)
		)
		(instances
			(project "gmsl-deserializer"
				(path ""
					(page "4")
				)
			)
		)
	)
	(sheet
		(at 148.59 199.39)
		(size 45.72 39.37)
		(exclude_from_sim no)
		(in_bom yes)
		(on_board yes)
		(dnp no)
		(fields_autoplaced yes)
		(stroke
			(width 0.1524)
			(type solid)
		)
		(fill
			(color 0 0 0 0.0000)
		)
		(property "Sheetname" "Connectors"
			(at 148.59 198.6784 0)
			(effects
				(font
					(size 1.27 1.27)
				)
				(justify left bottom)
			)
		)
		(property "Sheetfile" "connectors.kicad_sch"
			(at 148.59 239.3446 0)
			(effects
				(font
					(size 1.27 1.27)
				)
				(justify left top)
			)
		)
		(pin "MFP[0..8]" bidirectional
			(at 194.31 220.98 0)
			(effects
				(font
					(size 1.27 1.27)
				)
				(justify right)
			)
		)
		(pin "CSI0{CSI}" input
			(at 194.31 223.52 0)
			(effects
				(font
					(size 1.27 1.27)
				)
				(justify right)
			)
		)
		(pin "CSI1{CSI}" input
			(at 194.31 226.06 0)
			(effects
				(font
					(size 1.27 1.27)
				)
				(justify right)
			)
		)
		(pin "SDA" bidirectional
			(at 194.31 232.41 0)
			(effects
				(font
					(size 1.27 1.27)
				)
				(justify right)
			)
		)
		(pin "SCL" output
			(at 194.31 234.95 0)
			(effects
				(font
					(size 1.27 1.27)
				)
				(justify right)
			)
		)
		(pin "SIOCP" bidirectional
			(at 194.31 209.55 0)
			(effects
				(font
					(size 1.27 1.27)
				)
				(justify right)
			)
		)
		(pin "SIOAP" bidirectional
			(at 194.31 204.47 0)
			(effects
				(font
					(size 1.27 1.27)
				)
				(justify right)
			)
		)
		(pin "SIOBP" bidirectional
			(at 194.31 207.01 0)
			(effects
				(font
					(size 1.27 1.27)
				)
				(justify right)
			)
		)
		(pin "SIODP" bidirectional
			(at 194.31 212.09 0)
			(effects
				(font
					(size 1.27 1.27)
				)
				(justify right)
			)
		)
		(pin "PoCB" input
			(at 148.59 207.01 180)
			(effects
				(font
					(size 1.27 1.27)
				)
				(justify left)
			)
		)
		(pin "PoCC" input
			(at 148.59 209.55 180)
			(effects
				(font
					(size 1.27 1.27)
				)
				(justify left)
			)
		)
		(pin "PoCA" input
			(at 148.59 204.47 180)
			(effects
				(font
					(size 1.27 1.27)
				)
				(justify left)
			)
		)
		(pin "PoCD" input
			(at 148.59 212.09 180)
			(effects
				(font
					(size 1.27 1.27)
				)
				(justify left)
			)
		)
		(pin "FFC_5V" output
			(at 148.59 228.6 180)
			(effects
				(font
					(size 1.27 1.27)
				)
				(justify left)
			)
		)
		(pin "DC_IN" output
			(at 148.59 223.52 180)
			(effects
				(font
					(size 1.27 1.27)
				)
				(justify left)
			)
		)
		(instances
			(project "gmsl-deserializer"
				(path ""
					(page "2")
				)
			)
		)
	)
	(sheet_instances
		(path "/"
			(page "1")
		)
	)
)
